(kicad_pcb
	(version 20241229)
	(generator "pcbnew")
	(generator_version "9.0")
	(general
		(thickness 1.711)
		(legacy_teardrops no)
	)
	(paper "A4")
	(title_block
		(title "Antmicro Baseboard for Jetson AGX Thor")
		(date "2026-02-18")
		(rev "1.1.0")
		(company "Antmicro Ltd")
		(comment 1 "www.antmicro.com")
		(comment 9 "footprints 6-10 of 1170")
	)
	(layers
		(0 "F.Cu" signal)
		(4 "In1.Cu" signal)
		(6 "In2.Cu" signal)
		(8 "In3.Cu" signal)
		(10 "In4.Cu" jumper)
		(12 "In5.Cu" signal)
		(14 "In6.Cu" signal)
		(16 "In7.Cu" signal)
		(18 "In8.Cu" signal)
		(2 "B.Cu" signal)
		(9 "F.Adhes" user "F.Adhesive")
		(11 "B.Adhes" user "B.Adhesive")
		(13 "F.Paste" user)
		(15 "B.Paste" user)
		(5 "F.SilkS" user "F.Silkscreen")
		(7 "B.SilkS" user "B.Silkscreen")
		(1 "F.Mask" user)
		(3 "B.Mask" user)
		(17 "Dwgs.User" user "User.Drawings")
		(19 "Cmts.User" user "User.Comments")
		(21 "Eco1.User" user "User.Eco1")
		(23 "Eco2.User" user "User.Eco2")
		(25 "Edge.Cuts" user)
		(27 "Margin" user)
		(31 "F.CrtYd" user "F.Courtyard")
		(29 "B.CrtYd" user "B.Courtyard")
		(35 "F.Fab" user)
		(33 "B.Fab" user)
	)
	(footprint "antmicro-footprints:C_0402_1005Metric"
		(layer "F.Cu")
		(at 213.544132 84.292 -90)
		(descr "Capacitor SMD 0402")
		(tags "capacitor SMD 0402")
		(property "Reference" "C130"
			(at -3.682 0.324132 90)
			(layer "F.SilkS")
			(effects
				(font
					(size 0.7 0.7)
					(thickness 0.15)
				)
				(justify right top)
			)
		)
		(property "Value" "C_100n_0402"
			(at -1.022927 2.155213 90)
			(layer "F.Fab")
			(effects
				(font
					(size 0.7 0.7)
					(thickness 0.15)
				)
				(justify right top)
			)
		)
		(property "Datasheet" "https://www.murata.com/products/productdetail?partno=GRM155R61H104KE14%23"
			(at 0 0 90)
			(layer "F.Fab")
			(hide yes)
			(effects
				(font
					(size 1.27 1.27)
					(thickness 0.15)
				)
			)
		)
		(property "Description" "SMD Multilayer Ceramic Capacitor, 0.1 µF, 50 V, 0402 [1005 Metric], ± 10%, X5R, GRM Series"
			(at 0 0 90)
			(layer "F.Fab")
			(hide yes)
			(effects
				(font
					(size 1.27 1.27)
					(thickness 0.15)
				)
			)
		)
		(property "Manufacturer" "Murata"
			(at 0 0 270)
			(unlocked yes)
			(layer "F.Fab")
			(hide yes)
			(effects
				(font
					(size 1 1)
					(thickness 0.15)
				)
			)
		)
		(property "MPN" "GRM155R61H104KE14D"
			(at 0 0 270)
			(unlocked yes)
			(layer "F.Fab")
			(hide yes)
			(effects
				(font
					(size 1 1)
					(thickness 0.15)
				)
			)
		)
		(property "Val" "100n"
			(at 0 0 270)
			(unlocked yes)
			(layer "F.Fab")
			(hide yes)
			(effects
				(font
					(size 1 1)
					(thickness 0.15)
				)
			)
		)
		(property "License" "Apache-2.0"
			(at 0 0 270)
			(unlocked yes)
			(layer "F.Fab")
			(hide yes)
			(effects
				(font
					(size 1 1)
					(thickness 0.15)
				)
			)
		)
		(property "Author" "Antmicro"
			(at 0 0 270)
			(unlocked yes)
			(layer "F.Fab")
			(hide yes)
			(effects
				(font
					(size 1 1)
					(thickness 0.15)
				)
			)
		)
		(property "Voltage" "50V"
			(at 0 0 270)
			(unlocked yes)
			(layer "F.Fab")
			(hide yes)
			(effects
				(font
					(size 1 1)
					(thickness 0.15)
				)
			)
		)
		(property "Dielectric" "X5R"
			(at 0 0 270)
			(unlocked yes)
			(layer "F.Fab")
			(hide yes)
			(effects
				(font
					(size 1 1)
					(thickness 0.15)
				)
			)
		)
		(sheetname "/USB DP Alt mode/")
		(sheetfile "usb_dp.kicad_sch")
		(attr smd)
		(fp_rect
			(start -0.925 -0.47)
			(end 0.925 0.47)
			(stroke
				(width 0.05)
				(type default)
			)
			(fill no)
			(layer "F.CrtYd")
		)
		(fp_line
			(start -0.494 0.248)
			(end -0.494 -0.25)
			(stroke
				(width 0.15)
				(type solid)
			)
			(layer "F.Fab")
		)
		(fp_line
			(start 0.504 0.248)
			(end -0.494 0.248)
			(stroke
				(width 0.15)
				(type solid)
			)
			(layer "F.Fab")
		)
		(fp_line
			(start -0.494 -0.25)
			(end 0.504 -0.25)
			(stroke
				(width 0.15)
				(type solid)
			)
			(layer "F.Fab")
		)
		(fp_line
			(start 0.504 -0.25)
			(end 0.504 0.248)
			(stroke
				(width 0.15)
				(type solid)
			)
			(layer "F.Fab")
		)
		(fp_text user "${REFERENCE}"
			(at -0.939 4.599 90)
			(layer "F.Fab")
			(effects
				(font
					(size 0.7 0.7)
					(thickness 0.15)
				)
				(justify right top)
			)
		)
		(fp_text user "Author: Antmicro"
			(at -0.939 3.399 90)
			(layer "F.Fab")
			(effects
				(font
					(size 0.7 0.7)
					(thickness 0.15)
				)
				(justify right top)
			)
		)
		(fp_text user "License: Apache-2.0"
			(at -0.939 5.799 90)
			(layer "F.Fab")
			(effects
				(font
					(size 0.7 0.7)
					(thickness 0.15)
				)
				(justify right top)
			)
		)
		(pad "1" smd roundrect
			(at -0.48 0 270)
			(size 0.59 0.64)
			(layers "F.Cu" "F.Mask" "F.Paste")
			(roundrect_rratio 0.25)
			(net 311 "/SoM_IO2/USBSS1.TX+")
			(pintype "passive")
		)
		(pad "2" smd roundrect
			(at 0.48 0 270)
			(size 0.59 0.64)
			(layers "F.Cu" "F.Mask" "F.Paste")
			(roundrect_rratio 0.25)
			(net 333 "/USB DP Alt mode/USBSS1_TX_C_N")
			(pintype "passive")
		)
	)
	(footprint "antmicro-footprints:C_0402_1005Metric"
		(layer "F.Cu")
		(at 89.1 94.1)
		(descr "Capacitor SMD 0402")
		(tags "capacitor SMD 0402")
		(property "Reference" "C335"
			(at -3.82 0.45 0)
			(layer "F.SilkS")
			(effects
				(font
					(size 0.7 0.7)
					(thickness 0.15)
				)
				(justify left bottom)
			)
		)
		(property "Value" "C_100n_0402"
			(at -1.022927 2.155213 0)
			(layer "F.Fab")
			(effects
				(font
					(size 0.7 0.7)
					(thickness 0.15)
				)
				(justify left bottom)
			)
		)
		(property "Datasheet" "https://www.murata.com/products/productdetail?partno=GRM155R61H104KE14%23"
			(at 0 0 0)
			(layer "F.Fab")
			(hide yes)
			(effects
				(font
					(size 1.27 1.27)
					(thickness 0.15)
				)
			)
		)
		(property "Description" "SMD Multilayer Ceramic Capacitor, 0.1 µF, 50 V, 0402 [1005 Metric], ± 10%, X5R, GRM Series"
			(at 0 0 0)
			(layer "F.Fab")
			(hide yes)
			(effects
				(font
					(size 1.27 1.27)
					(thickness 0.15)
				)
			)
		)
		(property "Manufacturer" "Murata"
			(at 0 0 0)
			(unlocked yes)
			(layer "F.Fab")
			(hide yes)
			(effects
				(font
					(size 1 1)
					(thickness 0.15)
				)
			)
		)
		(property "MPN" "GRM155R61H104KE14D"
			(at 0 0 0)
			(unlocked yes)
			(layer "F.Fab")
			(hide yes)
			(effects
				(font
					(size 1 1)
					(thickness 0.15)
				)
			)
		)
		(property "Val" "100n"
			(at 0 0 0)
			(unlocked yes)
			(layer "F.Fab")
			(hide yes)
			(effects
				(font
					(size 1 1)
					(thickness 0.15)
				)
			)
		)
		(property "License" "Apache-2.0"
			(at 0 0 0)
			(unlocked yes)
			(layer "F.Fab")
			(hide yes)
			(effects
				(font
					(size 1 1)
					(thickness 0.15)
				)
			)
		)
		(property "Author" "Antmicro"
			(at 0 0 0)
			(unlocked yes)
			(layer "F.Fab")
			(hide yes)
			(effects
				(font
					(size 1 1)
					(thickness 0.15)
				)
			)
		)
		(property "Voltage" "50V"
			(at 0 0 0)
			(unlocked yes)
			(layer "F.Fab")
			(hide yes)
			(effects
				(font
					(size 1 1)
					(thickness 0.15)
				)
			)
		)
		(property "Dielectric" "X5R"
			(at 0 0 0)
			(unlocked yes)
			(layer "F.Fab")
			(hide yes)
			(effects
				(font
					(size 1 1)
					(thickness 0.15)
				)
			)
		)
		(sheetname "/SoM_IO2/")
		(sheetfile "som_io2.kicad_sch")
		(attr smd)
		(fp_rect
			(start -0.925 -0.47)
			(end 0.925 0.47)
			(stroke
				(width 0.05)
				(type default)
			)
			(fill no)
			(layer "F.CrtYd")
		)
		(fp_line
			(start -0.494 -0.25)
			(end 0.504 -0.25)
			(stroke
				(width 0.15)
				(type solid)
			)
			(layer "F.Fab")
		)
		(fp_line
			(start -0.494 0.248)
			(end -0.494 -0.25)
			(stroke
				(width 0.15)
				(type solid)
			)
			(layer "F.Fab")
		)
		(fp_line
			(start 0.504 -0.25)
			(end 0.504 0.248)
			(stroke
				(width 0.15)
				(type solid)
			)
			(layer "F.Fab")
		)
		(fp_line
			(start 0.504 0.248)
			(end -0.494 0.248)
			(stroke
				(width 0.15)
				(type solid)
			)
			(layer "F.Fab")
		)
		(fp_text user "Author: Antmicro"
			(at -0.939 3.399 0)
			(layer "F.Fab")
			(effects
				(font
					(size 0.7 0.7)
					(thickness 0.15)
				)
				(justify left bottom)
			)
		)
		(fp_text user "${REFERENCE}"
			(at -0.939 4.599 0)
			(layer "F.Fab")
			(effects
				(font
					(size 0.7 0.7)
					(thickness 0.15)
				)
				(justify left bottom)
			)
		)
		(fp_text user "License: Apache-2.0"
			(at -0.939 5.799 0)
			(layer "F.Fab")
			(effects
				(font
					(size 0.7 0.7)
					(thickness 0.15)
				)
				(justify left bottom)
			)
		)
		(pad "1" smd roundrect
			(at -0.48 0)
			(size 0.59 0.64)
			(layers "F.Cu" "F.Mask" "F.Paste")
			(roundrect_rratio 0.25)
			(net 726 "/Expansion connector/DP2.TX1+")
			(pintype "passive")
		)
		(pad "2" smd roundrect
			(at 0.48 0)
			(size 0.59 0.64)
			(layers "F.Cu" "F.Mask" "F.Paste")
			(roundrect_rratio 0.25)
			(net 1255 "/SoM_IO2/DP2.TX1_C+")
			(pintype "passive")
		)
	)
	(footprint "antmicro-footprints:R_0402_1005Metric"
		(layer "F.Cu")
		(at 63.22 85.93 -90)
		(descr "Resistor SMD 0402")
		(tags "resistor SMD 0402")
		(property "Reference" "R166"
			(at -3.73 0.42 90)
			(layer "F.SilkS")
			(effects
				(font
					(size 0.7 0.7)
					(thickness 0.15)
				)
				(justify right top)
			)
		)
		(property "Value" "R_100k_0402"
			(at -1.011843 1.772047 90)
			(layer "F.Fab")
			(effects
				(font
					(size 0.7 0.7)
					(thickness 0.15)
				)
				(justify right top)
			)
		)
		(property "Datasheet" "https://www.bourns.com/docs/product-datasheets/cr.pdf"
			(at 0 0 90)
			(layer "F.Fab")
			(hide yes)
			(effects
				(font
					(size 1.27 1.27)
					(thickness 0.15)
				)
			)
		)
		(property "Description" "SMD Chip Resistor, 100 kohm, ± 1%, 62.5 mW, 0402 [1005 Metric], Thick Film, General Purpose"
			(at 0 0 90)
			(layer "F.Fab")
			(hide yes)
			(effects
				(font
					(size 1.27 1.27)
					(thickness 0.15)
				)
			)
		)
		(property "Manufacturer" "Bourns"
			(at 0 0 270)
			(unlocked yes)
			(layer "F.Fab")
			(hide yes)
			(effects
				(font
					(size 1 1)
					(thickness 0.15)
				)
			)
		)
		(property "MPN" "CR0402-FX-1003GLF"
			(at 0 0 270)
			(unlocked yes)
			(layer "F.Fab")
			(hide yes)
			(effects
				(font
					(size 1 1)
					(thickness 0.15)
				)
			)
		)
		(property "Val" "100k"
			(at 0 0 270)
			(unlocked yes)
			(layer "F.Fab")
			(hide yes)
			(effects
				(font
					(size 1 1)
					(thickness 0.15)
				)
			)
		)
		(property "License" "Apache-2.0"
			(at 0 0 270)
			(unlocked yes)
			(layer "F.Fab")
			(hide yes)
			(effects
				(font
					(size 1 1)
					(thickness 0.15)
				)
			)
		)
		(property "Author" "Antmicro"
			(at 0 0 270)
			(unlocked yes)
			(layer "F.Fab")
			(hide yes)
			(effects
				(font
					(size 1 1)
					(thickness 0.15)
				)
			)
		)
		(property "Tolerance" "1%"
			(at 0 0 270)
			(unlocked yes)
			(layer "F.Fab")
			(hide yes)
			(effects
				(font
					(size 1 1)
					(thickness 0.15)
				)
			)
		)
		(sheetname "/CSI/")
		(sheetfile "csi.kicad_sch")
		(attr smd)
		(fp_rect
			(start -0.925 -0.47)
			(end 0.925 0.47)
			(stroke
				(width 0.05)
				(type default)
			)
			(fill no)
			(layer "F.CrtYd")
		)
		(fp_rect
			(start -0.5 -0.25)
			(end 0.5 0.25)
			(stroke
				(width 0.15)
				(type solid)
			)
			(fill no)
			(layer "F.Fab")
		)
		(fp_text user "${REFERENCE}"
			(at -0.95 3.168 90)
			(layer "F.Fab")
			(effects
				(font
					(size 0.7 0.7)
					(thickness 0.15)
				)
				(justify right top)
			)
		)
		(fp_text user "Author: Antmicro"
			(at -0.95 4.169 90)
			(layer "F.Fab")
			(effects
				(font
					(size 0.7 0.7)
					(thickness 0.15)
				)
				(justify right top)
			)
		)
		(fp_text user "License: Apache-2.0"
			(at -0.95 5.169 90)
			(layer "F.Fab")
			(effects
				(font
					(size 0.7 0.7)
					(thickness 0.15)
				)
				(justify right top)
			)
		)
		(pad "1" smd roundrect
			(at -0.48 0 270)
			(size 0.59 0.64)
			(layers "F.Cu" "F.Mask" "F.Paste")
			(roundrect_rratio 0.25)
			(net 1 "GND")
			(pintype "passive")
		)
		(pad "2" smd roundrect
			(at 0.48 0 270)
			(size 0.59 0.64)
			(layers "F.Cu" "F.Mask" "F.Paste")
			(roundrect_rratio 0.25)
			(net 74 "/CSI/CAM_CTRL.CSIA_PEN")
			(pintype "passive")
		)
	)
	(footprint "antmicro-footprints:C_0402_1005Metric"
		(layer "F.Cu")
		(at 206.88 134.8 90)
		(descr "Capacitor SMD 0402")
		(tags "capacitor SMD 0402")
		(property "Reference" "C255"
			(at -1.6 13.9 90)
			(layer "F.SilkS")
			(effects
				(font
					(size 0.7 0.7)
					(thickness 0.15)
				)
				(justify left bottom)
			)
		)
		(property "Value" "C_100n_0402"
			(at -1.022927 2.155213 90)
			(layer "F.Fab")
			(effects
				(font
					(size 0.7 0.7)
					(thickness 0.15)
				)
				(justify left bottom)
			)
		)
		(property "Datasheet" "https://www.murata.com/products/productdetail?partno=GRM155R61H104KE14%23"
			(at 0 0 90)
			(layer "F.Fab")
			(hide yes)
			(effects
				(font
					(size 1.27 1.27)
					(thickness 0.15)
				)
			)
		)
		(property "Description" "SMD Multilayer Ceramic Capacitor, 0.1 µF, 50 V, 0402 [1005 Metric], ± 10%, X5R, GRM Series"
			(at 0 0 90)
			(layer "F.Fab")
			(hide yes)
			(effects
				(font
					(size 1.27 1.27)
					(thickness 0.15)
				)
			)
		)
		(property "Manufacturer" "Murata"
			(at 0 0 90)
			(unlocked yes)
			(layer "F.Fab")
			(hide yes)
			(effects
				(font
					(size 1 1)
					(thickness 0.15)
				)
			)
		)
		(property "MPN" "GRM155R61H104KE14D"
			(at 0 0 90)
			(unlocked yes)
			(layer "F.Fab")
			(hide yes)
			(effects
				(font
					(size 1 1)
					(thickness 0.15)
				)
			)
		)
		(property "Val" "100n"
			(at 0 0 90)
			(unlocked yes)
			(layer "F.Fab")
			(hide yes)
			(effects
				(font
					(size 1 1)
					(thickness 0.15)
				)
			)
		)
		(property "License" "Apache-2.0"
			(at 0 0 90)
			(unlocked yes)
			(layer "F.Fab")
			(hide yes)
			(effects
				(font
					(size 1 1)
					(thickness 0.15)
				)
			)
		)
		(property "Author" "Antmicro"
			(at 0 0 90)
			(unlocked yes)
			(layer "F.Fab")
			(hide yes)
			(effects
				(font
					(size 1 1)
					(thickness 0.15)
				)
			)
		)
		(property "Voltage" "50V"
			(at 0 0 90)
			(unlocked yes)
			(layer "F.Fab")
			(hide yes)
			(effects
				(font
					(size 1 1)
					(thickness 0.15)
				)
			)
		)
		(property "Dielectric" "X5R"
			(at 0 0 90)
			(unlocked yes)
			(layer "F.Fab")
			(hide yes)
			(effects
				(font
					(size 1 1)
					(thickness 0.15)
				)
			)
		)
		(sheetname "/USB Hub/")
		(sheetfile "usb_hub.kicad_sch")
		(attr smd)
		(fp_rect
			(start -0.925 -0.47)
			(end 0.925 0.47)
			(stroke
				(width 0.05)
				(type default)
			)
			(fill no)
			(layer "F.CrtYd")
		)
		(fp_line
			(start 0.504 -0.25)
			(end 0.504 0.248)
			(stroke
				(width 0.15)
				(type solid)
			)
			(layer "F.Fab")
		)
		(fp_line
			(start -0.494 -0.25)
			(end 0.504 -0.25)
			(stroke
				(width 0.15)
				(type solid)
			)
			(layer "F.Fab")
		)
		(fp_line
			(start 0.504 0.248)
			(end -0.494 0.248)
			(stroke
				(width 0.15)
				(type solid)
			)
			(layer "F.Fab")
		)
		(fp_line
			(start -0.494 0.248)
			(end -0.494 -0.25)
			(stroke
				(width 0.15)
				(type solid)
			)
			(layer "F.Fab")
		)
		(fp_text user "License: Apache-2.0"
			(at -0.939 5.799 90)
			(layer "F.Fab")
			(effects
				(font
					(size 0.7 0.7)
					(thickness 0.15)
				)
				(justify left bottom)
			)
		)
		(fp_text user "Author: Antmicro"
			(at -0.939 3.399 90)
			(layer "F.Fab")
			(effects
				(font
					(size 0.7 0.7)
					(thickness 0.15)
				)
				(justify left bottom)
			)
		)
		(fp_text user "${REFERENCE}"
			(at -0.939 4.599 90)
			(layer "F.Fab")
			(effects
				(font
					(size 0.7 0.7)
					(thickness 0.15)
				)
				(justify left bottom)
			)
		)
		(pad "1" smd roundrect
			(at -0.48 0 90)
			(size 0.59 0.64)
			(layers "F.Cu" "F.Mask" "F.Paste")
			(roundrect_rratio 0.25)
			(net 623 "/SoM_IO2/USBSS2.RX-")
			(pintype "passive")
		)
		(pad "2" smd roundrect
			(at 0.48 0 90)
			(size 0.59 0.64)
			(layers "F.Cu" "F.Mask" "F.Paste")
			(roundrect_rratio 0.25)
			(net 1134 "/USB Hub/USBSS_TX_N")
			(pintype "passive")
		)
	)
	(footprint "antmicro-footprints:C_0805_2012Metric"
		(layer "F.Cu")
		(at 130.129997 57.539999 180)
		(descr "Capacitor SMD 0805")
		(tags "capacitor SMD 0805")
		(property "Reference" "C370"
			(at 9.929997 -8.840001 0)
			(layer "F.SilkS")
			(effects
				(font
					(size 0.7 0.7)
					(thickness 0.15)
				)
				(justify left bottom)
			)
		)
		(property "Value" "C_22u_25V_0805"
			(at -2.055717 1.963153 0)
			(layer "F.Fab")
			(effects
				(font
					(size 0.7 0.7)
					(thickness 0.15)
				)
				(justify right top)
			)
		)
		(property "Datasheet" "https://product.samsungsem.com/mlcc/CL21A226MAYNNN.do"
			(at 0 0 0)
			(layer "F.Fab")
			(hide yes)
			(effects
				(font
					(size 1.27 1.27)
					(thickness 0.15)
				)
			)
		)
		(property "Description" "SMT Multilayer Ceramic Capacitor, 22uF, +/-20%, 25V, X5R, 0805 [2012 Metric]"
			(at 0 0 0)
			(layer "F.Fab")
			(hide yes)
			(effects
				(font
					(size 1.27 1.27)
					(thickness 0.15)
				)
			)
		)
		(property "MPN" "CL21A226MAYNNNE"
			(at 0 0 180)
			(unlocked yes)
			(layer "F.Fab")
			(hide yes)
			(effects
				(font
					(size 1 1)
					(thickness 0.15)
				)
			)
		)
		(property "Manufacturer" "Samsung Electro-Mechanics"
			(at 0 0 180)
			(unlocked yes)
			(layer "F.Fab")
			(hide yes)
			(effects
				(font
					(size 1 1)
					(thickness 0.15)
				)
			)
		)
		(property "License" "Apache-2.0"
			(at 0 0 180)
			(unlocked yes)
			(layer "F.Fab")
			(hide yes)
			(effects
				(font
					(size 1 1)
					(thickness 0.15)
				)
			)
		)
		(property "Author" "Antmicro"
			(at 0 0 180)
			(unlocked yes)
			(layer "F.Fab")
			(hide yes)
			(effects
				(font
					(size 1 1)
					(thickness 0.15)
				)
			)
		)
		(property "Val" "22u"
			(at 0 0 180)
			(unlocked yes)
			(layer "F.Fab")
			(hide yes)
			(effects
				(font
					(size 1 1)
					(thickness 0.15)
				)
			)
		)
		(property "Voltage" "25V"
			(at 0 0 180)
			(unlocked yes)
			(layer "F.Fab")
			(hide yes)
			(effects
				(font
					(size 1 1)
					(thickness 0.15)
				)
			)
		)
		(property "Dielectric" "X5R"
			(at 0 0 180)
			(unlocked yes)
			(layer "F.Fab")
			(hide yes)
			(effects
				(font
					(size 1 1)
					(thickness 0.15)
				)
			)
		)
		(property "Public" "False"
			(at 0 0 180)
			(unlocked yes)
			(layer "F.Fab")
			(hide yes)
			(effects
				(font
					(size 1 1)
					(thickness 0.15)
				)
			)
		)
		(sheetname "/DCDC/")
		(sheetfile "dcdc.kicad_sch")
		(attr smd)
		(fp_line
			(start -0.3 0.7)
			(end 0.3 0.7)
			(stroke
				(width 0.15)
				(type solid)
			)
			(layer "F.SilkS")
		)
		(fp_line
			(start -0.3 -0.7)
			(end 0.3 -0.7)
			(stroke
				(width 0.15)
				(type solid)
			)
			(layer "F.SilkS")
		)
		(fp_poly
			(pts
				(xy 1.95 -0.9) (xy 1.95 0.9) (xy -1.95 0.9) (xy -1.95 -0.9)
			)
			(stroke
				(width 0.05)
				(type default)
			)
			(fill no)
			(layer "F.CrtYd")
		)
		(fp_poly
			(pts
				(xy -0.95 -0.675001) (xy -0.95 0.675001) (xy 0.95 0.675001) (xy 0.95 -0.675001)
			)
			(stroke
				(width 0.15)
				(type solid)
			)
			(fill no)
			(layer "F.Fab")
		)
		(fp_text user "License: Apache-2.0"
			(at -1.9 4.947 0)
			(layer "F.Fab")
			(effects
				(font
					(size 0.7 0.7)
					(thickness 0.15)
				)
				(justify right top)
			)
		)
		(fp_text user "Author: Antmicro"
			(at -1.9 5.947 0)
			(layer "F.Fab")
			(effects
				(font
					(size 0.7 0.7)
					(thickness 0.15)
				)
				(justify right top)
			)
		)
		(fp_text user "${REFERENCE}"
			(at -1.899999 3.947 0)
			(layer "F.Fab")
			(effects
				(font
					(size 0.7 0.7)
					(thickness 0.15)
				)
				(justify right top)
			)
		)
		(pad "1" smd roundrect
			(at -1.099999 0 180)
			(size 1.2 1.3)
			(layers "F.Cu" "F.Mask" "F.Paste")
			(roundrect_rratio 0.25)
			(net 1 "GND")
			(pintype "passive")
		)
		(pad "2" smd roundrect
			(at 1.099999 0 180)
			(size 1.2 1.3)
			(layers "F.Cu" "F.Mask" "F.Paste")
			(roundrect_rratio 0.25)
			(net 13 "VCC")
			(pintype "passive")
		)
	)
)
